# T6G (Grand Teton) — schematic netlist excerpt (pin names and nets, part order shuffled) for the footprints in the layout excerpt that follows; sources: Cadence DE-HDL packaged netlist, KiCad conversion of 04192023_DAF0TMB3IC0_F0TG_MB_C_brd_V02_OCP.brd

PC104  Q_CAPP  270UF 16V 20% OSCON  pkg THLF  page 201 : A = SW_P12V_AUX_PVDDCR_CPU1_P0_FLT ; B = GND
R3595  Q_RES  33.2 1% CHIP  pkg 0402LF  page 251 : A = SMB_INA230_3V3AUX_SDA ; B = SMB_INA230_4_3V3AUX_SDA_R

Q102  MOSFET_NCH_DUAL  PJT138K IC  pkg SOT363XD  page 126
  S1  = GND
  G1  = GPU_BASE_HMC_READY
  D2  = GPU_BASE_HMC_READY_ISO
  S2  = GND
  G2  = GPU_BASE_HMC_READY_N
  D1  = GPU_BASE_HMC_READY_N

(kicad_pcb
	(version 20260206)
	(generator "pcbnew")
	(generator_version "10.0")
	(general
		(thickness 1.6)
		(legacy_teardrops no)
	)
	(paper "A4")
	(title_block
		(title "04192023_DAF0TMB3IC0_F0TG_MB_C_brd_V02_OCP.brd")
		(comment 1 "Grand Teton / footprints 1821-1823 of 8354")
	)
	(layers
		(0 "F.Cu" signal "TOP")
		(4 "In1.Cu" signal "GND")
		(6 "In2.Cu" signal "IN1")
		(8 "In3.Cu" signal "GND1")
		(10 "In4.Cu" signal "IN2")
		(12 "In5.Cu" signal "GND2")
		(14 "In6.Cu" signal "IN3")
		(16 "In7.Cu" signal "GND3")
		(18 "In8.Cu" signal "VCC")
		(20 "In9.Cu" signal "VCC1")
		(22 "In10.Cu" signal "GND4")
		(24 "In11.Cu" signal "IN4")
		(26 "In12.Cu" signal "GND5")
		(28 "In13.Cu" signal "IN5")
		(30 "In14.Cu" signal "GND6")
		(32 "In15.Cu" signal "IN6")
		(34 "In16.Cu" signal "GND7")
		(2 "B.Cu" signal "BOTTOM")
		(9 "F.Adhes" user "F.Adhesive")
		(11 "B.Adhes" user "B.Adhesive")
		(13 "F.Paste" user "Package Geometry/Pastemask Top")
		(15 "B.Paste" user "Package Geometry/Pastemask Bottom")
		(5 "F.SilkS" user "Ref Des/Silkscreen Top")
		(7 "B.SilkS" user "Ref Des/Silkscreen Bottom")
		(1 "F.Mask" user "Board Geometry/Soldermask Top")
		(3 "B.Mask" user "Board Geometry/Soldermask Bottom")
		(17 "Dwgs.User" user "User.Drawings")
		(19 "Cmts.User" user "User.Comments")
		(21 "Eco1.User" user "User.Eco1")
		(23 "Eco2.User" user "User.Eco2")
		(25 "Edge.Cuts" user "Board Geometry/Outline")
		(27 "Margin" user)
		(31 "F.CrtYd" user "Package Geometry/Place Bound Top")
		(29 "B.CrtYd" user "Package Geometry/Place Bound Bottom")
		(35 "F.Fab" user "Ref Des/Assembly Top")
		(33 "B.Fab" user "Ref Des/Assembly Bottom")
	)
	(footprint ""
		(layer "F.Cu")
		(at 152.982676 -50.739294 90)
		(property "Reference" "R3595"
			(at 0 0 90)
			(layer "F.SilkS")
			(hide yes)
			(effects
				(font
					(size 1.27 1.27)
				)
			)
		)
		(property "Value" ""
			(at 0 0 90)
			(layer "F.Fab")
			(effects
				(font
					(size 1.27 1.27)
				)
			)
		)
		(duplicate_pad_numbers_are_jumpers no)
		(fp_line
			(start 0.7874 -0.4064)
			(end 0.7874 0.4064)
			(stroke
				(width 0.1524)
				(type default)
			)
			(layer "F.SilkS")
		)
		(fp_line
			(start -0.7874 -0.4064)
			(end 0.7874 -0.4064)
			(stroke
				(width 0.1524)
				(type default)
			)
			(layer "F.SilkS")
		)
		(fp_line
			(start 0.7874 0.4064)
			(end -0.7874 0.4064)
			(stroke
				(width 0.1524)
				(type default)
			)
			(layer "F.SilkS")
		)
		(fp_line
			(start -0.7874 0.4064)
			(end -0.7874 -0.4064)
			(stroke
				(width 0.1524)
				(type default)
			)
			(layer "F.SilkS")
		)
		(fp_line
			(start -0.12065 -0.305054)
			(end -0.12065 -0.2794)
			(stroke
				(width 0.1)
				(type default)
			)
			(layer "F.Fab")
		)
		(fp_line
			(start -0.67945 -0.305054)
			(end -0.12065 -0.305054)
			(stroke
				(width 0.1)
				(type default)
			)
			(layer "F.Fab")
		)
		(fp_line
			(start 0.67945 -0.3048)
			(end 0.67945 0.3048)
			(stroke
				(width 0.1)
				(type default)
			)
			(layer "F.Fab")
		)
		(fp_line
			(start 0.12065 -0.3048)
			(end 0.67945 -0.3048)
			(stroke
				(width 0.1)
				(type default)
			)
			(layer "F.Fab")
		)
		(fp_line
			(start 0.12065 -0.2794)
			(end 0.12065 -0.3048)
			(stroke
				(width 0.1)
				(type default)
			)
			(layer "F.Fab")
		)
		(fp_line
			(start -0.12065 -0.2794)
			(end 0.12065 -0.2794)
			(stroke
				(width 0.1)
				(type default)
			)
			(layer "F.Fab")
		)
		(fp_line
			(start 0.120396 0.2794)
			(end -0.12065 0.2794)
			(stroke
				(width 0.1)
				(type default)
			)
			(layer "F.Fab")
		)
		(fp_line
			(start -0.12065 0.2794)
			(end -0.12065 0.3048)
			(stroke
				(width 0.1)
				(type default)
			)
			(layer "F.Fab")
		)
		(fp_line
			(start 0.67945 0.3048)
			(end 0.120396 0.3048)
			(stroke
				(width 0.1)
				(type default)
			)
			(layer "F.Fab")
		)
		(fp_line
			(start 0.120396 0.3048)
			(end 0.120396 0.2794)
			(stroke
				(width 0.1)
				(type default)
			)
			(layer "F.Fab")
		)
		(fp_line
			(start -0.12065 0.3048)
			(end -0.67945 0.3048)
			(stroke
				(width 0.1)
				(type default)
			)
			(layer "F.Fab")
		)
		(fp_line
			(start -0.67945 0.3048)
			(end -0.67945 -0.305054)
			(stroke
				(width 0.1)
				(type default)
			)
			(layer "F.Fab")
		)
		(pad "1" smd circle
			(at -0.40005 0 90)
			(size 0 0)
			(layers "F.Cu" "F.Mask" "F.Paste")
			(net "SMB_INA230_3V3AUX_SDA")
		)
		(pad "2" smd circle
			(at 0.40005 0 90)
			(size 0 0)
			(layers "F.Cu" "F.Mask" "F.Paste")
			(net "SMB_INA230_4_3V3AUX_SDA_R")
		)
	)
	(footprint ""
		(layer "F.Cu")
		(at 335.411064 -349.43161 180)
		(property "Reference" "PC104"
			(at 0.115316 -2.938272 0)
			(unlocked yes)
			(layer "F.SilkS")
			(effects
				(font
					(size 0.7874 0.5842)
					(thickness 0.1524)
				)
				(justify left)
			)
		)
		(property "Value" ""
			(at 0 0 180)
			(layer "F.Fab")
			(effects
				(font
					(size 1.27 1.27)
				)
			)
		)
		(duplicate_pad_numbers_are_jumpers no)
		(fp_line
			(start -3.400044 1.249934)
			(end 3.400044 1.249934)
			(stroke
				(width 0.1524)
				(type default)
			)
			(layer "F.SilkS")
		)
		(fp_circle
			(center 0 1.249934)
			(end -3.400044 1.249934)
			(stroke
				(width 0.1524)
				(type default)
			)
			(fill no)
			(layer "F.SilkS")
		)
		(fp_poly
			(pts
				(arc
					(start 3.400044 1.249934)
					(mid 0 4.649978)
					(end -3.400044 1.249934)
				)
			)
			(stroke
				(width 0)
				(type default)
			)
			(fill yes)
			(layer "F.SilkS")
		)
		(fp_circle
			(center 0 1.249934)
			(end -3.400044 1.249934)
			(stroke
				(width 0.1)
				(type default)
			)
			(fill no)
			(layer "F.Fab")
		)
		(pad "1" thru_hole rect
			(at 0 0 180)
			(size 1.524 1.524)
			(drill 1.016)
			(layers "*.Cu" "*.Mask")
			(remove_unused_layers no)
			(net "SW_P12V_AUX_PVDDCR_CPU1_P0_FLT")
			(clearance 0)
			(padstack
				(mode front_inner_back)
				(layer "Inner"
					(shape circle)
					(size 1.524 1.524)
					(clearance 0)
				)
				(layer "B.Cu"
					(shape rect)
					(size 1.524 1.524)
					(clearance 0)
				)
			)
		)
		(pad "2" thru_hole circle
			(at 0 2.500122 180)
			(size 1.524 1.524)
			(drill 1.016)
			(layers "*.Cu" "*.Mask")
			(remove_unused_layers no)
			(net "GND")
			(clearance 0)
		)
	)
	(footprint ""
		(layer "F.Cu")
		(at 167.871902 -436.78221)
		(property "Reference" "Q102"
			(at 2.473706 1.534414 0)
			(unlocked yes)
			(layer "F.SilkS")
			(effects
				(font
					(size 0.7874 0.5842)
					(thickness 0.1524)
				)
				(justify left)
			)
		)
		(property "Value" ""
			(at 0 0 0)
			(layer "F.Fab")
			(effects
				(font
					(size 1.27 1.27)
				)
			)
		)
		(duplicate_pad_numbers_are_jumpers no)
		(fp_line
			(start -1.332738 -1.100074)
			(end -0.4826 -1.100074)
			(stroke
				(width 0.1524)
				(type default)
			)
			(layer "F.SilkS")
		)
		(fp_line
			(start -1.332738 1.100074)
			(end -1.332738 -1.100074)
			(stroke
				(width 0.1524)
				(type default)
			)
			(layer "F.SilkS")
		)
		(fp_line
			(start -0.4826 -1.100074)
			(end 0 -0.541274)
			(stroke
				(width 0.1524)
				(type default)
			)
			(layer "F.SilkS")
		)
		(fp_line
			(start 0 -0.541274)
			(end 0.4826 -1.100074)
			(stroke
				(width 0.1524)
				(type default)
			)
			(layer "F.SilkS")
		)
		(fp_line
			(start 0.4826 -1.100074)
			(end 1.332738 -1.100074)
			(stroke
				(width 0.1524)
				(type default)
			)
			(layer "F.SilkS")
		)
		(fp_line
			(start 1.332738 -1.100074)
			(end 1.332738 1.100074)
			(stroke
				(width 0.1524)
				(type default)
			)
			(layer "F.SilkS")
		)
		(fp_line
			(start 1.332738 1.100074)
			(end -1.332738 1.100074)
			(stroke
				(width 0.1524)
				(type default)
			)
			(layer "F.SilkS")
		)
		(fp_poly
			(pts
				(xy -1.429766 -1.020064) (xy -2.15773 -1.313688) (xy -1.631696 -1.778508)
			)
			(stroke
				(width 0)
				(type default)
			)
			(fill yes)
			(layer "F.SilkS")
		)
		(fp_line
			(start -0.674878 -1.100074)
			(end 0.674878 -1.100074)
			(stroke
				(width 0.1)
				(type default)
			)
			(layer "F.Fab")
		)
		(fp_line
			(start -0.674878 1.100074)
			(end -0.674878 -1.100074)
			(stroke
				(width 0.1)
				(type default)
			)
			(layer "F.Fab")
		)
		(fp_line
			(start 0.674878 -1.100074)
			(end 0.674878 1.100074)
			(stroke
				(width 0.1)
				(type default)
			)
			(layer "F.Fab")
		)
		(fp_line
			(start 0.674878 1.100074)
			(end -0.674878 1.100074)
			(stroke
				(width 0.1)
				(type default)
			)
			(layer "F.Fab")
		)
		(fp_poly
			(pts
				(xy -2.2352 -0.298958) (xy -2.2352 -1.001014) (xy -1.533144 -0.649986)
			)
			(stroke
				(width 0)
				(type default)
			)
			(fill yes)
			(layer "F.Fab")
		)
		(pad "1" smd rect
			(at -0.94996 -0.649986 90)
			(size 0.4318 0.508)
			(layers "F.Cu" "F.Mask" "F.Paste")
			(net "GND")
		)
		(pad "2" smd rect
			(at -0.94996 0 90)
			(size 0.4318 0.508)
			(layers "F.Cu" "F.Mask" "F.Paste")
			(net "GPU_BASE_HMC_READY")
		)
		(pad "3" smd rect
			(at -0.94996 0.649986 90)
			(size 0.4318 0.508)
			(layers "F.Cu" "F.Mask" "F.Paste")
			(net "GPU_BASE_HMC_READY_ISO")
		)
		(pad "4" smd rect
			(at 0.94996 0.649986 90)
			(size 0.4318 0.508)
			(layers "F.Cu" "F.Mask" "F.Paste")
			(net "GND")
		)
		(pad "5" smd rect
			(at 0.94996 0 90)
			(size 0.4318 0.508)
			(layers "F.Cu" "F.Mask" "F.Paste")
			(net "GPU_BASE_HMC_READY_N")
		)
		(pad "6" smd rect
			(at 0.94996 -0.649986 90)
			(size 0.4318 0.508)
			(layers "F.Cu" "F.Mask" "F.Paste")
			(net "GPU_BASE_HMC_READY_N")
		)
	)
)
